# T6G (Grand Teton) — schematic netlist excerpt (pin names and nets, part order shuffled) for the footprints in the layout excerpt that follows; sources: Cadence DE-HDL packaged netlist, KiCad conversion of 04192023_DAF0TMB3IC0_F0TG_MB_C_brd_V02_OCP.brd

C2156  Q_CAP  22UF 4V 20% X6S  pkg C0402  page 68 : A = PVDD11_S3_P0 ; B = GND
PR361  Q_RES  5.6 1% CHIP  pkg 0402LF  page 198 : A = SW_PVDDCR_SOC_P0_BOOT2 ; B = SW_PVDDCR_SOC_P0_BOOT2_RC

(kicad_pcb
	(version 20260206)
	(generator "pcbnew")
	(generator_version "10.0")
	(general
		(thickness 1.6)
		(legacy_teardrops no)
	)
	(paper "A4")
	(title_block
		(title "04192023_DAF0TMB3IC0_F0TG_MB_C_brd_V02_OCP.brd")
		(comment 1 "Grand Teton / footprints 3882-3883 of 8354")
	)
	(layers
		(0 "F.Cu" signal "TOP")
		(4 "In1.Cu" signal "GND")
		(6 "In2.Cu" signal "IN1")
		(8 "In3.Cu" signal "GND1")
		(10 "In4.Cu" signal "IN2")
		(12 "In5.Cu" signal "GND2")
		(14 "In6.Cu" signal "IN3")
		(16 "In7.Cu" signal "GND3")
		(18 "In8.Cu" signal "VCC")
		(20 "In9.Cu" signal "VCC1")
		(22 "In10.Cu" signal "GND4")
		(24 "In11.Cu" signal "IN4")
		(26 "In12.Cu" signal "GND5")
		(28 "In13.Cu" signal "IN5")
		(30 "In14.Cu" signal "GND6")
		(32 "In15.Cu" signal "IN6")
		(34 "In16.Cu" signal "GND7")
		(2 "B.Cu" signal "BOTTOM")
		(9 "F.Adhes" user "F.Adhesive")
		(11 "B.Adhes" user "B.Adhesive")
		(13 "F.Paste" user "Package Geometry/Pastemask Top")
		(15 "B.Paste" user "Package Geometry/Pastemask Bottom")
		(5 "F.SilkS" user "Ref Des/Silkscreen Top")
		(7 "B.SilkS" user "Ref Des/Silkscreen Bottom")
		(1 "F.Mask" user "Board Geometry/Soldermask Top")
		(3 "B.Mask" user "Board Geometry/Soldermask Bottom")
		(17 "Dwgs.User" user "User.Drawings")
		(19 "Cmts.User" user "User.Comments")
		(21 "Eco1.User" user "User.Eco1")
		(23 "Eco2.User" user "User.Eco2")
		(25 "Edge.Cuts" user "Board Geometry/Outline")
		(27 "Margin" user)
		(31 "F.CrtYd" user "Package Geometry/Place Bound Top")
		(29 "B.CrtYd" user "Package Geometry/Place Bound Bottom")
		(35 "F.Fab" user "Ref Des/Assembly Top")
		(33 "B.Fab" user "Ref Des/Assembly Bottom")
	)
	(footprint ""
		(layer "F.Cu")
		(at 405.388572 -163.942014 -90)
		(property "Reference" "PR361"
			(at 0 0 270)
			(layer "F.SilkS")
			(hide yes)
			(effects
				(font
					(size 1.27 1.27)
				)
			)
		)
		(property "Value" ""
			(at 0 0 270)
			(layer "F.Fab")
			(effects
				(font
					(size 1.27 1.27)
				)
			)
		)
		(duplicate_pad_numbers_are_jumpers no)
		(fp_line
			(start -0.7874 0.4064)
			(end -0.7874 -0.4064)
			(stroke
				(width 0.1524)
				(type default)
			)
			(layer "F.SilkS")
		)
		(fp_line
			(start 0.7874 0.4064)
			(end -0.7874 0.4064)
			(stroke
				(width 0.1524)
				(type default)
			)
			(layer "F.SilkS")
		)
		(fp_line
			(start -0.7874 -0.4064)
			(end 0.7874 -0.4064)
			(stroke
				(width 0.1524)
				(type default)
			)
			(layer "F.SilkS")
		)
		(fp_line
			(start 0.7874 -0.4064)
			(end 0.7874 0.4064)
			(stroke
				(width 0.1524)
				(type default)
			)
			(layer "F.SilkS")
		)
		(fp_line
			(start -0.67945 0.3048)
			(end -0.67945 -0.305054)
			(stroke
				(width 0.1)
				(type default)
			)
			(layer "F.Fab")
		)
		(fp_line
			(start -0.12065 0.3048)
			(end -0.67945 0.3048)
			(stroke
				(width 0.1)
				(type default)
			)
			(layer "F.Fab")
		)
		(fp_line
			(start 0.120396 0.3048)
			(end 0.120396 0.2794)
			(stroke
				(width 0.1)
				(type default)
			)
			(layer "F.Fab")
		)
		(fp_line
			(start 0.67945 0.3048)
			(end 0.120396 0.3048)
			(stroke
				(width 0.1)
				(type default)
			)
			(layer "F.Fab")
		)
		(fp_line
			(start -0.12065 0.2794)
			(end -0.12065 0.3048)
			(stroke
				(width 0.1)
				(type default)
			)
			(layer "F.Fab")
		)
		(fp_line
			(start 0.120396 0.2794)
			(end -0.12065 0.2794)
			(stroke
				(width 0.1)
				(type default)
			)
			(layer "F.Fab")
		)
		(fp_line
			(start -0.12065 -0.2794)
			(end 0.12065 -0.2794)
			(stroke
				(width 0.1)
				(type default)
			)
			(layer "F.Fab")
		)
		(fp_line
			(start 0.12065 -0.2794)
			(end 0.12065 -0.3048)
			(stroke
				(width 0.1)
				(type default)
			)
			(layer "F.Fab")
		)
		(fp_line
			(start 0.12065 -0.3048)
			(end 0.67945 -0.3048)
			(stroke
				(width 0.1)
				(type default)
			)
			(layer "F.Fab")
		)
		(fp_line
			(start 0.67945 -0.3048)
			(end 0.67945 0.3048)
			(stroke
				(width 0.1)
				(type default)
			)
			(layer "F.Fab")
		)
		(fp_line
			(start -0.67945 -0.305054)
			(end -0.12065 -0.305054)
			(stroke
				(width 0.1)
				(type default)
			)
			(layer "F.Fab")
		)
		(fp_line
			(start -0.12065 -0.305054)
			(end -0.12065 -0.2794)
			(stroke
				(width 0.1)
				(type default)
			)
			(layer "F.Fab")
		)
		(pad "1" smd circle
			(at -0.40005 0 270)
			(size 0 0)
			(layers "F.Cu" "F.Mask" "F.Paste")
			(net "SW_PVDDCR_SOC_P0_BOOT2")
		)
		(pad "2" smd circle
			(at 0.40005 0 270)
			(size 0 0)
			(layers "F.Cu" "F.Mask" "F.Paste")
			(net "SW_PVDDCR_SOC_P0_BOOT2_RC")
		)
	)
	(footprint ""
		(layer "F.Cu")
		(at 358.467152 -261.747762 -90)
		(property "Reference" "C2156"
			(at 0 0 270)
			(layer "F.SilkS")
			(hide yes)
			(effects
				(font
					(size 1.27 1.27)
				)
			)
		)
		(property "Value" ""
			(at 0 0 270)
			(layer "F.Fab")
			(effects
				(font
					(size 1.27 1.27)
				)
			)
		)
		(duplicate_pad_numbers_are_jumpers no)
		(fp_line
			(start -0.7874 0.4064)
			(end -0.7874 -0.4064)
			(stroke
				(width 0.1524)
				(type default)
			)
			(layer "F.SilkS")
		)
		(fp_line
			(start 0.7874 0.4064)
			(end -0.7874 0.4064)
			(stroke
				(width 0.1524)
				(type default)
			)
			(layer "F.SilkS")
		)
		(fp_line
			(start -0.7874 -0.4064)
			(end 0.7874 -0.4064)
			(stroke
				(width 0.1524)
				(type default)
			)
			(layer "F.SilkS")
		)
		(fp_line
			(start 0.7874 -0.4064)
			(end 0.7874 0.4064)
			(stroke
				(width 0.1524)
				(type default)
			)
			(layer "F.SilkS")
		)
		(fp_line
			(start -0.67945 0.3048)
			(end -0.67945 -0.305054)
			(stroke
				(width 0.1)
				(type default)
			)
			(layer "F.Fab")
		)
		(fp_line
			(start -0.12065 0.3048)
			(end -0.67945 0.3048)
			(stroke
				(width 0.1)
				(type default)
			)
			(layer "F.Fab")
		)
		(fp_line
			(start 0.120396 0.3048)
			(end 0.120396 0.2794)
			(stroke
				(width 0.1)
				(type default)
			)
			(layer "F.Fab")
		)
		(fp_line
			(start 0.67945 0.3048)
			(end 0.120396 0.3048)
			(stroke
				(width 0.1)
				(type default)
			)
			(layer "F.Fab")
		)
		(fp_line
			(start -0.12065 0.2794)
			(end -0.12065 0.3048)
			(stroke
				(width 0.1)
				(type default)
			)
			(layer "F.Fab")
		)
		(fp_line
			(start 0.120396 0.2794)
			(end -0.12065 0.2794)
			(stroke
				(width 0.1)
				(type default)
			)
			(layer "F.Fab")
		)
		(fp_line
			(start -0.12065 -0.2794)
			(end 0.12065 -0.2794)
			(stroke
				(width 0.1)
				(type default)
			)
			(layer "F.Fab")
		)
		(fp_line
			(start 0.12065 -0.2794)
			(end 0.12065 -0.3048)
			(stroke
				(width 0.1)
				(type default)
			)
			(layer "F.Fab")
		)
		(fp_line
			(start 0.12065 -0.3048)
			(end 0.67945 -0.3048)
			(stroke
				(width 0.1)
				(type default)
			)
			(layer "F.Fab")
		)
		(fp_line
			(start 0.67945 -0.3048)
			(end 0.67945 0.3048)
			(stroke
				(width 0.1)
				(type default)
			)
			(layer "F.Fab")
		)
		(fp_line
			(start -0.67945 -0.305054)
			(end -0.12065 -0.305054)
			(stroke
				(width 0.1)
				(type default)
			)
			(layer "F.Fab")
		)
		(fp_line
			(start -0.12065 -0.305054)
			(end -0.12065 -0.2794)
			(stroke
				(width 0.1)
				(type default)
			)
			(layer "F.Fab")
		)
		(pad "1" smd circle
			(at -0.40005 0 270)
			(size 0 0)
			(layers "F.Cu" "F.Mask" "F.Paste")
			(net "PVDD11_S3_P0")
		)
		(pad "2" smd circle
			(at 0.40005 0 270)
			(size 0 0)
			(layers "F.Cu" "F.Mask" "F.Paste")
			(net "GND")
		)
	)
)
